#ISCELL
  mstr_symbols intel_corp_bpage *
  *
#ISCELL
  mstr_standard offpage *
  page250_i1
#ISCELL
  mstr_standard offpage *
  page250_i10
#ISCELL
  mstr_standard offpage *
  page250_i11
#CELL
  mstr_discrete fet_n_dual *
  page250_i12
#ISCELL
  mstr_standard offpage *
  page250_i13
#ISCELL
  mstr_standard offpage *
  page250_i14
#ISCELL
  mstr_standard offpage *
  page250_i15
#ISCELL
  mstr_symbols gnd *
  page250_i16
#ISCELL
  mstr_symbols p3v3_stby *
  page250_i17
#CELL
  w_hdl 1mr2f-l-gp *
  page250_i18
#ISCELL
  mstr_symbols gnd *
  page250_i19
#CELL
  w_hdl 1mr2f-l-gp *
  page250_i2
#ISCELL
  mstr_symbols p3v3_stby *
  page250_i21
#CELL
  mstr_discrete res *
  page250_i22
#ISCELL
  mstr_symbols gnd *
  page250_i23
#CELL
  mstr_discrete fet_n_dual *
  page250_i24
#ISCELL
  mstr_standard offpage *
  page250_i25
#ISCELL
  mstr_symbols p3v3_stby *
  page250_i26
#CELL
  w_hdl 1mr2f-l-gp *
  page250_i27
#ISCELL
  mstr_standard offpage *
  page250_i28
#CELL
  mstr_discrete fet_n *
  page250_i29
#CELL
  mstr_discrete fet_n_dual *
  page250_i3
#ISCELL
  mstr_symbols gnd *
  page250_i4
#ISCELL
  mstr_symbols p3v3_stby *
  page250_i5
#CELL
  mstr_discrete res *
  page250_i6
#ISCELL
  mstr_symbols p3v3_stby *
  page250_i7
#CELL
  mstr_discrete fet_n_dual *
  page250_i8
#ISCELL
  mstr_symbols gnd *
  page250_i9
